(kicad_pcb
	(version 20260206)
	(generator "pcbnew")
	(generator_version "10.0")
	(general
		(thickness 1.6)
		(legacy_teardrops no)
	)
	(paper "A4")
	(title_block
		(title "pdpb — Lightning_PDPB_BRD.brd")
		(comment 1 "Lightning (Wiwynn / Facebook NVMe JBOF) / footprints 310-316 of 1140")
	)
	(layers
		(0 "F.Cu" signal "TOP")
		(4 "In1.Cu" signal "L2GND")
		(6 "In2.Cu" signal "L3")
		(8 "In3.Cu" signal "L4VCC")
		(10 "In4.Cu" signal "L5VCC")
		(12 "In5.Cu" signal "L6")
		(14 "In6.Cu" signal "L7GND")
		(2 "B.Cu" signal "BOTTOM")
		(9 "F.Adhes" user "F.Adhesive")
		(11 "B.Adhes" user "B.Adhesive")
		(13 "F.Paste" user "Package Geometry/Pastemask Top")
		(15 "B.Paste" user "Package Geometry/Pastemask Bottom")
		(5 "F.SilkS" user "Ref Des/Silkscreen Top")
		(7 "B.SilkS" user "Ref Des/Silkscreen Bottom")
		(1 "F.Mask" user "Board Geometry/Soldermask Top")
		(3 "B.Mask" user "Board Geometry/Soldermask Bottom")
		(17 "Dwgs.User" user "User.Drawings")
		(19 "Cmts.User" user "User.Comments")
		(21 "Eco1.User" user "User.Eco1")
		(23 "Eco2.User" user "User.Eco2")
		(25 "Edge.Cuts" user "Board Geometry/Outline")
		(27 "Margin" user)
		(31 "F.CrtYd" user "Package Geometry/Place Bound Top")
		(29 "B.CrtYd" user "Package Geometry/Place Bound Bottom")
		(35 "F.Fab" user "Ref Des/Assembly Top")
		(33 "B.Fab" user "Ref Des/Assembly Bottom")
	)
	(footprint ""
		(layer "F.Cu")
		(at 82.931 -311.531 90)
		(property "Reference" "R9352"
			(at 0 0 90)
			(layer "F.SilkS")
			(hide yes)
			(effects
				(font
					(size 1.27 1.27)
				)
			)
		)
		(property "Value" "2D2R2F-GP"
			(at 0.064008 -3.993896 90)
			(unlocked yes)
			(layer "F.Fab")
			(hide yes)
			(effects
				(font
					(size 1.016 1.016)
					(thickness 0.1524)
				)
			)
		)
		(property "Device Type" "R402H16"
			(at 0.064008 -5.517896 90)
			(unlocked yes)
			(layer "F.Fab")
			(hide yes)
			(effects
				(font
					(size 1.016 1.016)
					(thickness 0.1524)
				)
			)
		)
		(duplicate_pad_numbers_are_jumpers no)
		(fp_line
			(start 0.508 -0.9398)
			(end -0.508 -0.9398)
			(stroke
				(width 0.1524)
				(type default)
			)
			(layer "F.SilkS")
		)
		(fp_line
			(start -0.508 -0.9398)
			(end -0.508 0.9398)
			(stroke
				(width 0.1524)
				(type default)
			)
			(layer "F.SilkS")
		)
		(fp_rect
			(start -0.508 0.9398)
			(end 0.508 -0.9398)
			(stroke
				(width 0)
				(type default)
			)
			(fill no)
			(layer "F.CrtYd")
		)
		(fp_rect
			(start -0.508 0.9398)
			(end 0.508 -0.9398)
			(stroke
				(width 0)
				(type default)
			)
			(fill no)
			(layer "F.Fab")
		)
		(pad "1" smd custom
			(at 0 -0.4445 90)
			(size 0.1397 0.1397)
			(layers "F.Cu" "F.Mask" "F.Paste")
			(net "VDD_DIFF_2")
			(options
				(clearance outline)
				(anchor circle)
			)
			(primitives
				(gr_poly
					(pts
						(arc
							(start -0.1778 -0.2794)
							(mid -0.249642 -0.249642)
							(end -0.2794 -0.1778)
						)
						(arc
							(start -0.2794 0.1778)
							(mid -0.249642 0.249642)
							(end -0.1778 0.2794)
						)
						(arc
							(start 0.1778 0.2794)
							(mid 0.249642 0.249642)
							(end 0.2794 0.1778)
						)
						(arc
							(start 0.2794 -0.1778)
							(mid 0.249642 -0.249642)
							(end 0.1778 -0.2794)
						)
					)
					(width 0)
					(fill yes)
				)
			)
		)
		(pad "2" smd custom
			(at 0 0.4445 90)
			(size 0.1397 0.1397)
			(layers "F.Cu" "F.Mask" "F.Paste")
			(net "VDDA_2")
			(options
				(clearance outline)
				(anchor circle)
			)
			(primitives
				(gr_poly
					(pts
						(arc
							(start -0.1778 -0.2794)
							(mid -0.249642 -0.249642)
							(end -0.2794 -0.1778)
						)
						(arc
							(start -0.2794 0.1778)
							(mid -0.249642 0.249642)
							(end -0.1778 0.2794)
						)
						(arc
							(start 0.1778 0.2794)
							(mid 0.249642 0.249642)
							(end 0.2794 0.1778)
						)
						(arc
							(start 0.2794 -0.1778)
							(mid 0.249642 -0.249642)
							(end 0.1778 -0.2794)
						)
					)
					(width 0)
					(fill yes)
				)
			)
		)
	)
	(footprint ""
		(layer "F.Cu")
		(at 5.500116 -488.40009)
		(property "Reference" "H1"
			(at 0 0 0)
			(layer "F.SilkS")
			(hide yes)
			(effects
				(font
					(size 1.27 1.27)
				)
			)
		)
		(property "Value" "GEN276X162R197X296-6-F-A-GP"
			(at -6.7183 4.1402 0)
			(unlocked yes)
			(layer "F.Fab")
			(hide yes)
			(effects
				(font
					(size 1.016 1.016)
					(thickness 0.1524)
				)
			)
		)
		(property "Device Type" "GEN276X162R197X296-6-F-A"
			(at -6.7183 2.6162 0)
			(unlocked yes)
			(layer "F.Fab")
			(hide yes)
			(effects
				(font
					(size 1.016 1.016)
					(thickness 0.1524)
				)
			)
		)
		(duplicate_pad_numbers_are_jumpers no)
		(fp_poly
			(pts
				(arc
					(start 2.723642 4.777232)
					(mid -0.000169 6.508462)
					(end -2.723896 4.776978)
				)
				(arc
					(start -2.723896 4.776978)
					(mid 0.000173 -5.499012)
					(end 2.723642 4.777232)
				)
			)
			(stroke
				(width 0)
				(type default)
			)
			(fill no)
			(layer "B.CrtYd")
		)
		(fp_poly
			(pts
				(arc
					(start 2.723642 4.777232)
					(mid -0.000169 6.508462)
					(end -2.723896 4.776978)
				)
				(arc
					(start -2.723896 4.776978)
					(mid 0.000173 -5.499012)
					(end 2.723642 4.777232)
				)
			)
			(stroke
				(width 0)
				(type default)
			)
			(fill no)
			(layer "F.CrtYd")
		)
		(fp_poly
			(pts
				(arc
					(start 2.723642 4.777232)
					(mid -0.000169 6.508462)
					(end -2.723896 4.776978)
				)
				(arc
					(start -2.723896 4.776978)
					(mid 0.000173 -5.499012)
					(end 2.723642 4.777232)
				)
			)
			(stroke
				(width 0)
				(type default)
			)
			(fill no)
			(layer "B.Fab")
		)
		(fp_poly
			(pts
				(arc
					(start 2.723642 4.777232)
					(mid -0.000169 6.508462)
					(end -2.723896 4.776978)
				)
				(arc
					(start -2.723896 4.776978)
					(mid 0.000173 -5.499012)
					(end 2.723642 4.777232)
				)
			)
			(stroke
				(width 0)
				(type default)
			)
			(fill no)
			(layer "F.Fab")
		)
		(pad "" np_thru_hole circle
			(at 0 0)
			(size 0.254 0.254)
			(drill 0.0254)
			(layers "*.Cu" "*.Mask")
			(clearance 3.135376)
			(thermal_gap 3.135376)
		)
		(pad "1" thru_hole circle
			(at 2.549906 0)
			(size 0.8636 0.8636)
			(drill 0.508)
			(layers "*.Cu" "*.Mask")
			(remove_unused_layers no)
			(net "GND")
			(clearance 0.8255)
			(thermal_gap 0.8255)
		)
		(pad "2" thru_hole circle
			(at 2.210054 -1.27)
			(size 0.8636 0.8636)
			(drill 0.508)
			(layers "*.Cu" "*.Mask")
			(remove_unused_layers no)
			(net "GND")
			(clearance 0.8255)
			(thermal_gap 0.8255)
		)
		(pad "3" thru_hole circle
			(at 1.27 -2.210054)
			(size 0.8636 0.8636)
			(drill 0.508)
			(layers "*.Cu" "*.Mask")
			(remove_unused_layers no)
			(net "GND")
			(clearance 0.8255)
			(thermal_gap 0.8255)
		)
		(pad "4" thru_hole circle
			(at -1.279906 -2.210054)
			(size 0.8636 0.8636)
			(drill 0.508)
			(layers "*.Cu" "*.Mask")
			(remove_unused_layers no)
			(net "GND")
			(clearance 0.8255)
			(thermal_gap 0.8255)
		)
		(pad "5" thru_hole circle
			(at -2.210054 -1.27)
			(size 0.8636 0.8636)
			(drill 0.508)
			(layers "*.Cu" "*.Mask")
			(remove_unused_layers no)
			(net "GND")
			(clearance 0.8255)
			(thermal_gap 0.8255)
		)
		(pad "6" thru_hole circle
			(at -2.549906 0)
			(size 0.8636 0.8636)
			(drill 0.508)
			(layers "*.Cu" "*.Mask")
			(remove_unused_layers no)
			(net "GND")
			(clearance 0.8255)
			(thermal_gap 0.8255)
		)
		(zone
			(layers "F.Cu" "B.Cu" "In1.Cu" "In2.Cu" "In3.Cu" "In4.Cu" "In5.Cu" "In6.Cu")
			(hatch none 0.5)
			(connect_pads
				(clearance 0)
			)
			(min_thickness 0.25)
			(keepout
				(tracks allowed)
				(vias not_allowed)
				(pads allowed)
				(copperpour not_allowed)
				(footprints allowed)
			)
			(placement
				(enabled no)
				(sheetname "")
			)
			(fill
				(thermal_gap 0.5)
				(thermal_bridge_width 0.5)
				(island_removal_mode 0)
			)
			(polygon
				(pts
					(arc
						(start 9.818116 -488.403138)
						(mid 1.182116 -488.403138)
						(end 9.818116 -488.403138)
					)
				)
			)
		)
		(zone
			(layers "F.Cu" "B.Cu" "In1.Cu" "In2.Cu" "In3.Cu" "In4.Cu" "In5.Cu" "In6.Cu")
			(hatch none 0.5)
			(connect_pads
				(clearance 0)
			)
			(min_thickness 0.25)
			(keepout
				(tracks not_allowed)
				(vias allowed)
				(pads allowed)
				(copperpour not_allowed)
				(footprints allowed)
			)
			(placement
				(enabled no)
				(sheetname "")
			)
			(fill
				(thermal_gap 0.5)
				(thermal_bridge_width 0.5)
				(island_removal_mode 0)
			)
			(polygon
				(pts
					(arc
						(start 7.839456 -486.790746)
						(mid 5.500196 -481.891643)
						(end 3.160522 -486.790746)
					)
					(arc
						(start 3.160522 -486.790746)
						(mid 3.406489 -487.231112)
						(end 3.491738 -487.72826)
					)
					(arc
						(start 3.491738 -488.40009)
						(mid 5.500116 -490.408468)
						(end 7.50824 -488.40009)
					)
					(arc
						(start 7.50824 -487.72826)
						(mid 7.593475 -487.231106)
						(end 7.839456 -486.790746)
					)
				)
			)
		)
	)
	(footprint ""
		(layer "F.Cu")
		(at 207.391 -94.234 180)
		(property "Reference" "R9506"
			(at 0 0 180)
			(layer "F.SilkS")
			(hide yes)
			(effects
				(font
					(size 1.27 1.27)
				)
			)
		)
		(property "Value" "4K7R2J-2-GP"
			(at 0.064008 -3.993896 180)
			(unlocked yes)
			(layer "F.Fab")
			(hide yes)
			(effects
				(font
					(size 1.016 1.016)
					(thickness 0.1524)
				)
			)
		)
		(property "Device Type" "R402H16"
			(at 0.064008 -5.517896 180)
			(unlocked yes)
			(layer "F.Fab")
			(hide yes)
			(effects
				(font
					(size 1.016 1.016)
					(thickness 0.1524)
				)
			)
		)
		(duplicate_pad_numbers_are_jumpers no)
		(fp_line
			(start 0.508 -0.9398)
			(end -0.508 -0.9398)
			(stroke
				(width 0.1524)
				(type default)
			)
			(layer "F.SilkS")
		)
		(fp_line
			(start -0.508 -0.9398)
			(end -0.508 0.9398)
			(stroke
				(width 0.1524)
				(type default)
			)
			(layer "F.SilkS")
		)
		(fp_rect
			(start -0.508 0.9398)
			(end 0.508 -0.9398)
			(stroke
				(width 0)
				(type default)
			)
			(fill no)
			(layer "F.CrtYd")
		)
		(fp_rect
			(start -0.508 0.9398)
			(end 0.508 -0.9398)
			(stroke
				(width 0)
				(type default)
			)
			(fill no)
			(layer "F.Fab")
		)
		(pad "1" smd custom
			(at 0 -0.4445 180)
			(size 0.1397 0.1397)
			(layers "F.Cu" "F.Mask" "F.Paste")
			(net "P3V3")
			(options
				(clearance outline)
				(anchor circle)
			)
			(primitives
				(gr_poly
					(pts
						(arc
							(start -0.1778 -0.2794)
							(mid -0.249642 -0.249642)
							(end -0.2794 -0.1778)
						)
						(arc
							(start -0.2794 0.1778)
							(mid -0.249642 0.249642)
							(end -0.1778 0.2794)
						)
						(arc
							(start 0.1778 0.2794)
							(mid 0.249642 0.249642)
							(end 0.2794 0.1778)
						)
						(arc
							(start 0.2794 -0.1778)
							(mid 0.249642 -0.249642)
							(end 0.1778 -0.2794)
						)
					)
					(width 0)
					(fill yes)
				)
			)
		)
		(pad "2" smd custom
			(at 0 0.4445 180)
			(size 0.1397 0.1397)
			(layers "F.Cu" "F.Mask" "F.Paste")
			(net "SSD4_PWREN")
			(options
				(clearance outline)
				(anchor circle)
			)
			(primitives
				(gr_poly
					(pts
						(arc
							(start -0.1778 -0.2794)
							(mid -0.249642 -0.249642)
							(end -0.2794 -0.1778)
						)
						(arc
							(start -0.2794 0.1778)
							(mid -0.249642 0.249642)
							(end -0.1778 0.2794)
						)
						(arc
							(start 0.1778 0.2794)
							(mid 0.249642 0.249642)
							(end 0.2794 0.1778)
						)
						(arc
							(start 0.2794 -0.1778)
							(mid 0.249642 -0.249642)
							(end 0.1778 -0.2794)
						)
					)
					(width 0)
					(fill yes)
				)
			)
		)
	)
	(footprint ""
		(layer "F.Cu")
		(at 8.90905 -500.44985 90)
		(property "Reference" "R9813"
			(at 0 0 90)
			(layer "F.SilkS")
			(hide yes)
			(effects
				(font
					(size 1.27 1.27)
				)
			)
		)
		(property "Value" "1KR2J-1-GP"
			(at 0.064008 -3.993896 90)
			(unlocked yes)
			(layer "F.Fab")
			(hide yes)
			(effects
				(font
					(size 1.016 1.016)
					(thickness 0.1524)
				)
			)
		)
		(property "Device Type" "R402H16"
			(at 0.064008 -5.517896 90)
			(unlocked yes)
			(layer "F.Fab")
			(hide yes)
			(effects
				(font
					(size 1.016 1.016)
					(thickness 0.1524)
				)
			)
		)
		(duplicate_pad_numbers_are_jumpers no)
		(fp_line
			(start 0.508 -0.9398)
			(end -0.508 -0.9398)
			(stroke
				(width 0.1524)
				(type default)
			)
			(layer "F.SilkS")
		)
		(fp_line
			(start -0.508 -0.9398)
			(end -0.508 0.9398)
			(stroke
				(width 0.1524)
				(type default)
			)
			(layer "F.SilkS")
		)
		(fp_rect
			(start -0.508 0.9398)
			(end 0.508 -0.9398)
			(stroke
				(width 0)
				(type default)
			)
			(fill no)
			(layer "F.CrtYd")
		)
		(fp_rect
			(start -0.508 0.9398)
			(end 0.508 -0.9398)
			(stroke
				(width 0)
				(type default)
			)
			(fill no)
			(layer "F.Fab")
		)
		(pad "1" smd custom
			(at 0 -0.4445 90)
			(size 0.1397 0.1397)
			(layers "F.Cu" "F.Mask" "F.Paste")
			(net "SSD5_PWREN")
			(options
				(clearance outline)
				(anchor circle)
			)
			(primitives
				(gr_poly
					(pts
						(arc
							(start -0.1778 -0.2794)
							(mid -0.249642 -0.249642)
							(end -0.2794 -0.1778)
						)
						(arc
							(start -0.2794 0.1778)
							(mid -0.249642 0.249642)
							(end -0.1778 0.2794)
						)
						(arc
							(start 0.1778 0.2794)
							(mid 0.249642 0.249642)
							(end 0.2794 0.1778)
						)
						(arc
							(start 0.2794 -0.1778)
							(mid 0.249642 -0.249642)
							(end 0.1778 -0.2794)
						)
					)
					(width 0)
					(fill yes)
				)
			)
		)
		(pad "2" smd custom
			(at 0 0.4445 90)
			(size 0.1397 0.1397)
			(layers "F.Cu" "F.Mask" "F.Paste")
			(net "SSD5_PWREN_R")
			(options
				(clearance outline)
				(anchor circle)
			)
			(primitives
				(gr_poly
					(pts
						(arc
							(start -0.1778 -0.2794)
							(mid -0.249642 -0.249642)
							(end -0.2794 -0.1778)
						)
						(arc
							(start -0.2794 0.1778)
							(mid -0.249642 0.249642)
							(end -0.1778 0.2794)
						)
						(arc
							(start 0.1778 0.2794)
							(mid 0.249642 0.249642)
							(end 0.2794 0.1778)
						)
						(arc
							(start 0.2794 -0.1778)
							(mid 0.249642 -0.249642)
							(end 0.1778 -0.2794)
						)
					)
					(width 0)
					(fill yes)
				)
			)
		)
	)
	(footprint ""
		(layer "F.Cu")
		(at 25.7302 -307.7972 90)
		(property "Reference" "R9850"
			(at 0 0 90)
			(layer "F.SilkS")
			(hide yes)
			(effects
				(font
					(size 1.27 1.27)
				)
			)
		)
		(property "Value" "2K2R5F-GP"
			(at 0 -8.9535 90)
			(unlocked yes)
			(layer "F.Fab")
			(hide yes)
			(effects
				(font
					(size 1.27 1.016)
					(thickness 0.1524)
				)
			)
		)
		(property "Device Type" "R805H24"
			(at 0 -10.6299 90)
			(unlocked yes)
			(layer "F.Fab")
			(hide yes)
			(effects
				(font
					(size 1.27 1.016)
					(thickness 0.1524)
				)
			)
		)
		(duplicate_pad_numbers_are_jumpers no)
		(fp_line
			(start 0.889 -1.7018)
			(end -0.889 -1.7018)
			(stroke
				(width 0.1524)
				(type default)
			)
			(layer "F.SilkS")
		)
		(fp_line
			(start 0.889 -1.7018)
			(end 0.889 -0.381)
			(stroke
				(width 0.1524)
				(type default)
			)
			(layer "F.SilkS")
		)
		(fp_line
			(start -0.889 -1.7018)
			(end -0.889 0.2794)
			(stroke
				(width 0.1524)
				(type default)
			)
			(layer "F.SilkS")
		)
		(fp_line
			(start -0.889 0.0762)
			(end -0.889 1.7018)
			(stroke
				(width 0.1524)
				(type default)
			)
			(layer "F.SilkS")
		)
		(fp_line
			(start 0.889 1.7018)
			(end 0.889 -0.508)
			(stroke
				(width 0.1524)
				(type default)
			)
			(layer "F.SilkS")
		)
		(fp_line
			(start -0.889 1.7018)
			(end 0.889 1.7018)
			(stroke
				(width 0.1524)
				(type default)
			)
			(layer "F.SilkS")
		)
		(fp_poly
			(pts
				(xy 0.9652 -1.778) (xy 0.9652 1.778) (xy -0.9652 1.778) (xy -0.9652 -1.778)
			)
			(stroke
				(width 0)
				(type default)
			)
			(fill no)
			(layer "F.CrtYd")
		)
		(fp_rect
			(start -0.9652 1.778)
			(end 0.9652 -1.778)
			(stroke
				(width 0)
				(type default)
			)
			(fill no)
			(layer "F.Fab")
		)
		(pad "1" smd rect
			(at 0 -0.9652 90)
			(size 1.397 1.143)
			(layers "F.Cu" "F.Mask" "F.Paste")
			(net "P12V_SSD11")
		)
		(pad "2" smd rect
			(at 0 0.9652 90)
			(size 1.397 1.143)
			(layers "F.Cu" "F.Mask" "F.Paste")
			(net "P12V_MOST11_GATE_D")
		)
	)
	(footprint ""
		(layer "F.Cu")
		(at 228.9302 -402.4884)
		(property "Reference" "R9248"
			(at 0 0 0)
			(layer "F.SilkS")
			(hide yes)
			(effects
				(font
					(size 1.27 1.27)
				)
			)
		)
		(property "Value" "2R2010F-GP"
			(at 0.0762 -4.5466 0)
			(unlocked yes)
			(layer "F.Fab")
			(hide yes)
			(effects
				(font
					(size 1.016 1.016)
					(thickness 0.1524)
				)
			)
		)
		(property "Device Type" "R2010H26"
			(at 0.0762 -6.1468 0)
			(unlocked yes)
			(layer "F.Fab")
			(hide yes)
			(effects
				(font
					(size 1.016 1.016)
					(thickness 0.1524)
				)
			)
		)
		(duplicate_pad_numbers_are_jumpers no)
		(fp_line
			(start -3.302 -1.651)
			(end -3.302 1.651)
			(stroke
				(width 0.1524)
				(type default)
			)
			(layer "F.SilkS")
		)
		(fp_line
			(start -3.302 1.651)
			(end 3.302 1.651)
			(stroke
				(width 0.1524)
				(type default)
			)
			(layer "F.SilkS")
		)
		(fp_line
			(start 3.302 -1.651)
			(end -3.302 -1.651)
			(stroke
				(width 0.1524)
				(type default)
			)
			(layer "F.SilkS")
		)
		(fp_line
			(start 3.302 1.651)
			(end 3.302 -1.651)
			(stroke
				(width 0.1524)
				(type default)
			)
			(layer "F.SilkS")
		)
		(fp_rect
			(start -3.3782 1.7272)
			(end 3.3782 -1.7272)
			(stroke
				(width 0)
				(type default)
			)
			(fill no)
			(layer "F.CrtYd")
		)
		(fp_poly
			(pts
				(xy 3.3782 -1.7272) (xy -3.3782 -1.7272) (xy -3.3782 1.7272) (xy 3.3782 1.7272)
			)
			(stroke
				(width 0)
				(type default)
			)
			(fill no)
			(layer "F.Fab")
		)
		(pad "1" smd rect
			(at -2.3495 0)
			(size 1.143 2.794)
			(layers "F.Cu" "F.Mask" "F.Paste")
			(net "P12V_SSD1")
		)
		(pad "2" smd rect
			(at 2.3495 0)
			(size 1.143 2.794)
			(layers "F.Cu" "F.Mask" "F.Paste")
			(net "12V_PRECH_SSD1")
		)
	)
	(footprint ""
		(layer "F.Cu")
		(at 46.569884 -450.723 -90)
		(property "Reference" "R9815"
			(at 0 0 270)
			(layer "F.SilkS")
			(hide yes)
			(effects
				(font
					(size 1.27 1.27)
				)
			)
		)
		(property "Value" "0R2J-2-GP"
			(at 0.064008 -3.993896 270)
			(unlocked yes)
			(layer "F.Fab")
			(hide yes)
			(effects
				(font
					(size 1.016 1.016)
					(thickness 0.1524)
				)
			)
		)
		(property "Device Type" "R402H16"
			(at 0.064008 -5.517896 270)
			(unlocked yes)
			(layer "F.Fab")
			(hide yes)
			(effects
				(font
					(size 1.016 1.016)
					(thickness 0.1524)
				)
			)
		)
		(duplicate_pad_numbers_are_jumpers no)
		(fp_line
			(start -0.508 -0.9398)
			(end -0.508 0.9398)
			(stroke
				(width 0.1524)
				(type default)
			)
			(layer "F.SilkS")
		)
		(fp_line
			(start 0.508 -0.9398)
			(end -0.508 -0.9398)
			(stroke
				(width 0.1524)
				(type default)
			)
			(layer "F.SilkS")
		)
		(fp_rect
			(start -0.508 0.9398)
			(end 0.508 -0.9398)
			(stroke
				(width 0)
				(type default)
			)
			(fill no)
			(layer "F.CrtYd")
		)
		(fp_rect
			(start -0.508 0.9398)
			(end 0.508 -0.9398)
			(stroke
				(width 0)
				(type default)
			)
			(fill no)
			(layer "F.Fab")
		)
		(pad "1" smd custom
			(at 0 -0.4445 270)
			(size 0.1397 0.1397)
			(layers "F.Cu" "F.Mask" "F.Paste")
			(net "ATTN_LED_DR5_AND")
			(options
				(clearance outline)
				(anchor circle)
			)
			(primitives
				(gr_poly
					(pts
						(arc
							(start -0.1778 -0.2794)
							(mid -0.249642 -0.249642)
							(end -0.2794 -0.1778)
						)
						(arc
							(start -0.2794 0.1778)
							(mid -0.249642 0.249642)
							(end -0.1778 0.2794)
						)
						(arc
							(start 0.1778 0.2794)
							(mid 0.249642 0.249642)
							(end 0.2794 0.1778)
						)
						(arc
							(start 0.2794 -0.1778)
							(mid 0.249642 -0.249642)
							(end 0.1778 -0.2794)
						)
					)
					(width 0)
					(fill yes)
				)
			)
		)
		(pad "2" smd custom
			(at 0 0.4445 270)
			(size 0.1397 0.1397)
			(layers "F.Cu" "F.Mask" "F.Paste")
			(net "ATTN_LED_DR5_AND_R")
			(options
				(clearance outline)
				(anchor circle)
			)
			(primitives
				(gr_poly
					(pts
						(arc
							(start -0.1778 -0.2794)
							(mid -0.249642 -0.249642)
							(end -0.2794 -0.1778)
						)
						(arc
							(start -0.2794 0.1778)
							(mid -0.249642 0.249642)
							(end -0.1778 0.2794)
						)
						(arc
							(start 0.1778 0.2794)
							(mid 0.249642 0.249642)
							(end 0.2794 0.1778)
						)
						(arc
							(start 0.2794 -0.1778)
							(mid 0.249642 -0.249642)
							(end 0.1778 -0.2794)
						)
					)
					(width 0)
					(fill yes)
				)
			)
		)
	)
)
